(kicad_pcb
	(version 20260206)
	(generator "pcbnew")
	(generator_version "10.0")
	(general
		(thickness 1.6)
		(legacy_teardrops no)
	)
	(paper "A4")
	(title_block
		(title "04192023_DAF0TMB3IC0_F0TG_MB_C_brd_V02_OCP.brd")
		(comment 1 "Grand Teton / footprints 1-2 of 8354")
	)
	(layers
		(0 "F.Cu" signal "TOP")
		(4 "In1.Cu" signal "GND")
		(6 "In2.Cu" signal "IN1")
		(8 "In3.Cu" signal "GND1")
		(10 "In4.Cu" signal "IN2")
		(12 "In5.Cu" signal "GND2")
		(14 "In6.Cu" signal "IN3")
		(16 "In7.Cu" signal "GND3")
		(18 "In8.Cu" signal "VCC")
		(20 "In9.Cu" signal "VCC1")
		(22 "In10.Cu" signal "GND4")
		(24 "In11.Cu" signal "IN4")
		(26 "In12.Cu" signal "GND5")
		(28 "In13.Cu" signal "IN5")
		(30 "In14.Cu" signal "GND6")
		(32 "In15.Cu" signal "IN6")
		(34 "In16.Cu" signal "GND7")
		(2 "B.Cu" signal "BOTTOM")
		(9 "F.Adhes" user "F.Adhesive")
		(11 "B.Adhes" user "B.Adhesive")
		(13 "F.Paste" user "Package Geometry/Pastemask Top")
		(15 "B.Paste" user "Package Geometry/Pastemask Bottom")
		(5 "F.SilkS" user "Ref Des/Silkscreen Top")
		(7 "B.SilkS" user "Ref Des/Silkscreen Bottom")
		(1 "F.Mask" user "Board Geometry/Soldermask Top")
		(3 "B.Mask" user "Board Geometry/Soldermask Bottom")
		(17 "Dwgs.User" user "User.Drawings")
		(19 "Cmts.User" user "User.Comments")
		(21 "Eco1.User" user "User.Eco1")
		(23 "Eco2.User" user "User.Eco2")
		(25 "Edge.Cuts" user "Board Geometry/Outline")
		(27 "Margin" user)
		(31 "F.CrtYd" user "Package Geometry/Place Bound Top")
		(29 "B.CrtYd" user "Package Geometry/Place Bound Bottom")
		(35 "F.Fab" user "Ref Des/Assembly Top")
		(33 "B.Fab" user "Ref Des/Assembly Bottom")
	)
	(footprint ""
		(layer "F.Cu")
		(at 210.74888 -42.382948)
		(property "Reference" "R3529"
			(at 0 0 0)
			(layer "F.SilkS")
			(hide yes)
			(effects
				(font
					(size 1.27 1.27)
				)
			)
		)
		(property "Value" ""
			(at 0 0 0)
			(layer "F.Fab")
			(effects
				(font
					(size 1.27 1.27)
				)
			)
		)
		(duplicate_pad_numbers_are_jumpers no)
		(fp_line
			(start -0.7874 -0.4064)
			(end 0.7874 -0.4064)
			(stroke
				(width 0.1524)
				(type default)
			)
			(layer "F.SilkS")
		)
		(fp_line
			(start -0.7874 0.4064)
			(end -0.7874 -0.4064)
			(stroke
				(width 0.1524)
				(type default)
			)
			(layer "F.SilkS")
		)
		(fp_line
			(start 0.7874 -0.4064)
			(end 0.7874 0.4064)
			(stroke
				(width 0.1524)
				(type default)
			)
			(layer "F.SilkS")
		)
		(fp_line
			(start 0.7874 0.4064)
			(end -0.7874 0.4064)
			(stroke
				(width 0.1524)
				(type default)
			)
			(layer "F.SilkS")
		)
		(fp_line
			(start -0.67945 -0.305054)
			(end -0.12065 -0.305054)
			(stroke
				(width 0.1)
				(type default)
			)
			(layer "F.Fab")
		)
		(fp_line
			(start -0.67945 0.3048)
			(end -0.67945 -0.305054)
			(stroke
				(width 0.1)
				(type default)
			)
			(layer "F.Fab")
		)
		(fp_line
			(start -0.12065 -0.305054)
			(end -0.12065 -0.2794)
			(stroke
				(width 0.1)
				(type default)
			)
			(layer "F.Fab")
		)
		(fp_line
			(start -0.12065 -0.2794)
			(end 0.12065 -0.2794)
			(stroke
				(width 0.1)
				(type default)
			)
			(layer "F.Fab")
		)
		(fp_line
			(start -0.12065 0.2794)
			(end -0.12065 0.3048)
			(stroke
				(width 0.1)
				(type default)
			)
			(layer "F.Fab")
		)
		(fp_line
			(start -0.12065 0.3048)
			(end -0.67945 0.3048)
			(stroke
				(width 0.1)
				(type default)
			)
			(layer "F.Fab")
		)
		(fp_line
			(start 0.120396 0.2794)
			(end -0.12065 0.2794)
			(stroke
				(width 0.1)
				(type default)
			)
			(layer "F.Fab")
		)
		(fp_line
			(start 0.120396 0.3048)
			(end 0.120396 0.2794)
			(stroke
				(width 0.1)
				(type default)
			)
			(layer "F.Fab")
		)
		(fp_line
			(start 0.12065 -0.3048)
			(end 0.67945 -0.3048)
			(stroke
				(width 0.1)
				(type default)
			)
			(layer "F.Fab")
		)
		(fp_line
			(start 0.12065 -0.2794)
			(end 0.12065 -0.3048)
			(stroke
				(width 0.1)
				(type default)
			)
			(layer "F.Fab")
		)
		(fp_line
			(start 0.67945 -0.3048)
			(end 0.67945 0.3048)
			(stroke
				(width 0.1)
				(type default)
			)
			(layer "F.Fab")
		)
		(fp_line
			(start 0.67945 0.3048)
			(end 0.120396 0.3048)
			(stroke
				(width 0.1)
				(type default)
			)
			(layer "F.Fab")
		)
		(pad "1" smd circle
			(at -0.40005 0)
			(size 0 0)
			(layers "F.Cu" "F.Mask" "F.Paste")
			(net "P3V3_AUX")
		)
		(pad "2" smd circle
			(at 0.40005 0)
			(size 0 0)
			(layers "F.Cu" "F.Mask" "F.Paste")
			(net "SMB_PCIE_E1S_ISO_EN_R")
		)
	)
	(footprint ""
		(layer "F.Cu")
		(at 58.93308 -40.404034 180)
		(property "Reference" "R4066"
			(at 0 0 180)
			(layer "F.SilkS")
			(hide yes)
			(effects
				(font
					(size 1.27 1.27)
				)
			)
		)
		(property "Value" ""
			(at 0 0 180)
			(layer "F.Fab")
			(effects
				(font
					(size 1.27 1.27)
				)
			)
		)
		(duplicate_pad_numbers_are_jumpers no)
		(fp_line
			(start 0.7874 0.4064)
			(end -0.7874 0.4064)
			(stroke
				(width 0.1524)
				(type default)
			)
			(layer "F.SilkS")
		)
		(fp_line
			(start 0.7874 -0.4064)
			(end 0.7874 0.4064)
			(stroke
				(width 0.1524)
				(type default)
			)
			(layer "F.SilkS")
		)
		(fp_line
			(start -0.7874 0.4064)
			(end -0.7874 -0.4064)
			(stroke
				(width 0.1524)
				(type default)
			)
			(layer "F.SilkS")
		)
		(fp_line
			(start -0.7874 -0.4064)
			(end 0.7874 -0.4064)
			(stroke
				(width 0.1524)
				(type default)
			)
			(layer "F.SilkS")
		)
		(fp_line
			(start 0.67945 0.3048)
			(end 0.120396 0.3048)
			(stroke
				(width 0.1)
				(type default)
			)
			(layer "F.Fab")
		)
		(fp_line
			(start 0.67945 -0.3048)
			(end 0.67945 0.3048)
			(stroke
				(width 0.1)
				(type default)
			)
			(layer "F.Fab")
		)
		(fp_line
			(start 0.12065 -0.2794)
			(end 0.12065 -0.3048)
			(stroke
				(width 0.1)
				(type default)
			)
			(layer "F.Fab")
		)
		(fp_line
			(start 0.12065 -0.3048)
			(end 0.67945 -0.3048)
			(stroke
				(width 0.1)
				(type default)
			)
			(layer "F.Fab")
		)
		(fp_line
			(start 0.120396 0.3048)
			(end 0.120396 0.2794)
			(stroke
				(width 0.1)
				(type default)
			)
			(layer "F.Fab")
		)
		(fp_line
			(start 0.120396 0.2794)
			(end -0.12065 0.2794)
			(stroke
				(width 0.1)
				(type default)
			)
			(layer "F.Fab")
		)
		(fp_line
			(start -0.12065 0.3048)
			(end -0.67945 0.3048)
			(stroke
				(width 0.1)
				(type default)
			)
			(layer "F.Fab")
		)
		(fp_line
			(start -0.12065 0.2794)
			(end -0.12065 0.3048)
			(stroke
				(width 0.1)
				(type default)
			)
			(layer "F.Fab")
		)
		(fp_line
			(start -0.12065 -0.2794)
			(end 0.12065 -0.2794)
			(stroke
				(width 0.1)
				(type default)
			)
			(layer "F.Fab")
		)
		(fp_line
			(start -0.12065 -0.305054)
			(end -0.12065 -0.2794)
			(stroke
				(width 0.1)
				(type default)
			)
			(layer "F.Fab")
		)
		(fp_line
			(start -0.67945 0.3048)
			(end -0.67945 -0.305054)
			(stroke
				(width 0.1)
				(type default)
			)
			(layer "F.Fab")
		)
		(fp_line
			(start -0.67945 -0.305054)
			(end -0.12065 -0.305054)
			(stroke
				(width 0.1)
				(type default)
			)
			(layer "F.Fab")
		)
		(pad "1" smd circle
			(at -0.40005 0 180)
			(size 0 0)
			(layers "F.Cu" "F.Mask" "F.Paste")
			(net "P3V3_OCP_EN_2_R")
		)
		(pad "2" smd circle
			(at 0.40005 0 180)
			(size 0 0)
			(layers "F.Cu" "F.Mask" "F.Paste")
			(net "GND")
		)
	)
)
